(kicad_pcb
	(version 20241229)
	(generator "pcbnew")
	(generator_version "9.0")
	(general
		(thickness 1.63)
		(legacy_teardrops no)
	)
	(paper "A4")
	(title_block
		(title "CM4 Baseboard")
		(date "2026-01-05")
		(rev "1.1.1")
		(company "Antmicro Ltd")
		(comment 1 "www.antmicro.com")
		(comment 9 "footprints 67-68 of 506")
	)
	(layers
		(0 "F.Cu" signal)
		(4 "In1.Cu" power)
		(6 "In2.Cu" power)
		(8 "In3.Cu" signal)
		(10 "In4.Cu" signal)
		(2 "B.Cu" signal)
		(9 "F.Adhes" user "F.Adhesive")
		(11 "B.Adhes" user "B.Adhesive")
		(13 "F.Paste" user)
		(15 "B.Paste" user)
		(5 "F.SilkS" user "F.Silkscreen")
		(7 "B.SilkS" user "B.Silkscreen")
		(1 "F.Mask" user)
		(3 "B.Mask" user)
		(17 "Dwgs.User" user "User.Drawings")
		(19 "Cmts.User" user "User.Comments")
		(21 "Eco1.User" user "User.Eco1")
		(23 "Eco2.User" user "User.Eco2")
		(25 "Edge.Cuts" user)
		(27 "Margin" user)
		(31 "F.CrtYd" user "F.Courtyard")
		(29 "B.CrtYd" user "B.Courtyard")
		(35 "F.Fab" user)
		(33 "B.Fab" user)
	)
	(footprint "antmicro-footprints:Nexperia_DFN-10_2.5x1mm_P0.5mm"
		(layer "F.Cu")
		(at 140.092962 135.579 180)
		(property "Reference" "D810"
			(at 1.485 -0.3175 0)
			(layer "F.SilkS")
			(effects
				(font
					(size 0.7 0.7)
					(thickness 0.15)
				)
				(justify right bottom)
			)
		)
		(property "Value" "PUSB3F96X_PASS"
			(at -0.016 1.705 0)
			(layer "F.Fab")
			(effects
				(font
					(size 0.7 0.7)
					(thickness 0.15)
				)
				(justify right bottom)
			)
		)
		(property "Datasheet" "https://mouser.com/datasheet/2/916/PUSB3F96-1600324.pdf"
			(at 0 0 180)
			(layer "F.Fab")
			(hide yes)
			(effects
				(font
					(size 1.27 1.27)
					(thickness 0.15)
				)
			)
		)
		(property "Manufacturer" "Nexperia"
			(at 0 0 180)
			(unlocked yes)
			(layer "F.Fab")
			(hide yes)
			(effects
				(font
					(size 1 1)
					(thickness 0.15)
				)
			)
		)
		(property "MPN" "PUSB3F96X"
			(at 0 0 180)
			(unlocked yes)
			(layer "F.Fab")
			(hide yes)
			(effects
				(font
					(size 1 1)
					(thickness 0.15)
				)
			)
		)
		(property "Author" "Antmicro"
			(at 0 0 180)
			(unlocked yes)
			(layer "F.Fab")
			(hide yes)
			(effects
				(font
					(size 1 1)
					(thickness 0.15)
				)
			)
		)
		(property "License" "Apache-2.0"
			(at 0 0 180)
			(unlocked yes)
			(layer "F.Fab")
			(hide yes)
			(effects
				(font
					(size 1 1)
					(thickness 0.15)
				)
			)
		)
		(sheetname "/Peripherals/")
		(sheetfile "peripherals.kicad_sch")
		(attr smd)
		(fp_line
			(start 1.375 0.4)
			(end 1.375 -0.4)
			(stroke
				(width 0.15)
				(type solid)
			)
			(layer "F.SilkS")
		)
		(fp_line
			(start -1.375 -0.4)
			(end -1.375 0.4)
			(stroke
				(width 0.15)
				(type solid)
			)
			(layer "F.SilkS")
		)
		(fp_circle
			(center -1.4 0.7)
			(end -1.349 0.7)
			(stroke
				(width 0.15)
				(type solid)
			)
			(fill yes)
			(layer "F.SilkS")
		)
		(fp_rect
			(start -1.4 -0.725)
			(end 1.4 0.725)
			(stroke
				(width 0.05)
				(type solid)
			)
			(fill no)
			(layer "F.CrtYd")
		)
		(fp_line
			(start 1.25 0.5)
			(end 1.25 -0.5)
			(stroke
				(width 0.15)
				(type solid)
			)
			(layer "F.Fab")
		)
		(fp_line
			(start 1.25 -0.5)
			(end -1.25 -0.5)
			(stroke
				(width 0.15)
				(type solid)
			)
			(layer "F.Fab")
		)
		(fp_line
			(start -0.9 0.5)
			(end 1.25 0.5)
			(stroke
				(width 0.15)
				(type solid)
			)
			(layer "F.Fab")
		)
		(fp_line
			(start -1.25 0.15)
			(end -0.9 0.5)
			(stroke
				(width 0.15)
				(type solid)
			)
			(layer "F.Fab")
		)
		(fp_line
			(start -1.25 -0.5)
			(end -1.25 0.15)
			(stroke
				(width 0.15)
				(type solid)
			)
			(layer "F.Fab")
		)
		(fp_text user "Author: Antmicro"
			(at -1.367 4.905 180)
			(layer "F.Fab")
			(effects
				(font
					(size 0.7 0.7)
					(thickness 0.15)
				)
				(justify left bottom)
			)
		)
		(fp_text user "License: Apache-2.0"
			(at -1.367 6.105 180)
			(layer "F.Fab")
			(effects
				(font
					(size 0.7 0.7)
					(thickness 0.15)
				)
				(justify left bottom)
			)
		)
		(fp_text user "${REFERENCE}"
			(at -1.367 3.704 180)
			(layer "F.Fab")
			(effects
				(font
					(size 0.7 0.7)
					(thickness 0.15)
				)
				(justify left bottom)
			)
		)
		(pad "1" smd rect
			(at -1 0.3875 180)
			(size 0.2 0.475)
			(layers "F.Cu" "F.Mask" "F.Paste")
			(net 224 "/Compute module/GPIO.12{slash}RXD5")
			(pinfunction "CH1")
			(pintype "passive")
			(solder_mask_margin 0.05)
		)
		(pad "2" smd rect
			(at -0.5 0.3875 180)
			(size 0.2 0.475)
			(layers "F.Cu" "F.Mask" "F.Paste")
			(net 222 "/Compute module/GPIO.16")
			(pinfunction "CH2")
			(pintype "passive")
			(solder_mask_margin 0.05)
		)
		(pad "3" smd rect
			(at 0 0.3875 180)
			(size 0.2 0.475)
			(layers "F.Cu" "F.Mask" "F.Paste")
			(net 3 "GND")
			(pinfunction "GND")
			(pintype "passive")
			(solder_mask_margin 0.05)
		)
		(pad "4" smd rect
			(at 0.5 0.3875 180)
			(size 0.2 0.475)
			(layers "F.Cu" "F.Mask" "F.Paste")
			(net 220 "/Compute module/GPIO.20")
			(pinfunction "CH3")
			(pintype "passive")
			(solder_mask_margin 0.05)
		)
		(pad "5" smd rect
			(at 1 0.3875 180)
			(size 0.2 0.475)
			(layers "F.Cu" "F.Mask" "F.Paste")
			(net 218 "/Compute module/GPIO.21")
			(pinfunction "CH4")
			(pintype "passive")
			(solder_mask_margin 0.05)
		)
		(pad "6" smd rect
			(at 1 -0.3875 180)
			(size 0.2 0.475)
			(layers "F.Cu" "F.Mask" "F.Paste")
			(net 218 "/Compute module/GPIO.21")
			(pinfunction "CH4")
			(pintype "passive")
			(solder_mask_margin 0.05)
		)
		(pad "7" smd rect
			(at 0.5 -0.3875 180)
			(size 0.2 0.475)
			(layers "F.Cu" "F.Mask" "F.Paste")
			(net 220 "/Compute module/GPIO.20")
			(pinfunction "CH3")
			(pintype "passive")
			(solder_mask_margin 0.05)
		)
		(pad "8" smd rect
			(at 0 -0.3875 180)
			(size 0.2 0.475)
			(layers "F.Cu" "F.Mask" "F.Paste")
			(net 3 "GND")
			(pinfunction "GND")
			(pintype "passive")
			(solder_mask_margin 0.05)
		)
		(pad "9" smd rect
			(at -0.501 -0.3875 180)
			(size 0.2 0.475)
			(layers "F.Cu" "F.Mask" "F.Paste")
			(net 222 "/Compute module/GPIO.16")
			(pinfunction "CH2")
			(pintype "passive")
			(solder_mask_margin 0.05)
		)
		(pad "10" smd rect
			(at -1 -0.3875 180)
			(size 0.2 0.475)
			(layers "F.Cu" "F.Mask" "F.Paste")
			(net 224 "/Compute module/GPIO.12{slash}RXD5")
			(pinfunction "CH1")
			(pintype "passive")
			(solder_mask_margin 0.05)
		)
	)
	(footprint "antmicro-footprints:RJ45_X-2337992-8_Horizontal"
		(layer "F.Cu")
		(at 70.483512 131.631 180)
		(property "Reference" "J401"
			(at 8.783512 -2.919 180)
			(layer "F.SilkS")
			(effects
				(font
					(size 0.7 0.7)
					(thickness 0.15)
				)
				(justify left bottom)
			)
		)
		(property "Value" "Bus_RJ45_5-2337992-8"
			(at -2.6 22 180)
			(layer "F.Fab")
			(effects
				(font
					(size 0.7 0.7)
					(thickness 0.15)
				)
				(justify left bottom)
			)
		)
		(property "Datasheet" "https://www.te.com/commerce/DocumentDelivery/DDEController?Action=showdoc&DocId=Customer+Drawing%7F5-2337992-8%7FA%7Fpdf%7FEnglish%7FENG_CD_5-2337992-8_A.pdf%7F5-2337992-8"
			(at 0 0 180)
			(layer "F.Fab")
			(hide yes)
			(effects
				(font
					(size 1.27 1.27)
					(thickness 0.15)
				)
			)
		)
		(property "MPN" "5-2337992-8"
			(at 0 0 180)
			(unlocked yes)
			(layer "F.Fab")
			(hide yes)
			(effects
				(font
					(size 1 1)
					(thickness 0.15)
				)
			)
		)
		(property "Manufacturer" "TE Connectivity"
			(at 0 0 180)
			(unlocked yes)
			(layer "F.Fab")
			(hide yes)
			(effects
				(font
					(size 1 1)
					(thickness 0.15)
				)
			)
		)
		(property "Author" "Antmicro"
			(at 0 0 180)
			(unlocked yes)
			(layer "F.Fab")
			(hide yes)
			(effects
				(font
					(size 1 1)
					(thickness 0.15)
				)
			)
		)
		(property "License" "Apache-2.0"
			(at 0 0 180)
			(unlocked yes)
			(layer "F.Fab")
			(hide yes)
			(effects
				(font
					(size 1 1)
					(thickness 0.15)
				)
			)
		)
		(property ki_fp_filters "CONN18_5-2337992-8_TEC")
		(sheetname "/Ethernet/")
		(sheetfile "ethernet.kicad_sch")
		(attr through_hole)
		(fp_line
			(start 13.791 19.771)
			(end 13.791 7.217)
			(stroke
				(width 0.15)
				(type solid)
			)
			(layer "F.SilkS")
		)
		(fp_line
			(start 13.791 4.48)
			(end 13.791 -1.845)
			(stroke
				(width 0.15)
				(type solid)
			)
			(layer "F.SilkS")
		)
		(fp_line
			(start 13.791 -1.845)
			(end -2.363 -1.845)
			(stroke
				(width 0.15)
				(type solid)
			)
			(layer "F.SilkS")
		)
		(fp_line
			(start -2.363 19.771)
			(end 13.791 19.771)
			(stroke
				(width 0.15)
				(type solid)
			)
			(layer "F.SilkS")
		)
		(fp_line
			(start -2.363 7.217)
			(end -2.363 19.771)
			(stroke
				(width 0.15)
				(type solid)
			)
			(layer "F.SilkS")
		)
		(fp_line
			(start -2.363 -1.845)
			(end -2.363 4.48)
			(stroke
				(width 0.15)
				(type solid)
			)
			(layer "F.SilkS")
		)
		(fp_rect
			(start -2.4 -1.8)
			(end 13.9 19.999)
			(stroke
				(width 0.05)
				(type solid)
			)
			(fill no)
			(layer "F.CrtYd")
		)
		(fp_line
			(start 13.665 19.644)
			(end 13.665 -1.718)
			(stroke
				(width 0.15)
				(type solid)
			)
			(layer "F.Fab")
		)
		(fp_line
			(start 13.665 -1.718)
			(end -2.237 -1.718)
			(stroke
				(width 0.15)
				(type solid)
			)
			(layer "F.Fab")
		)
		(fp_line
			(start -2.237 19.644)
			(end 13.665 19.644)
			(stroke
				(width 0.15)
				(type solid)
			)
			(layer "F.Fab")
		)
		(fp_line
			(start -2.237 -1.718)
			(end -2.237 19.644)
			(stroke
				(width 0.15)
				(type solid)
			)
			(layer "F.Fab")
		)
		(fp_text user "${REFERENCE}"
			(at -2.644 23.4 180)
			(layer "F.Fab")
			(effects
				(font
					(size 0.7 0.7)
					(thickness 0.15)
				)
				(justify left bottom)
			)
		)
		(fp_text user "Author: Antmicro"
			(at -2.644 24.8 180)
			(layer "F.Fab")
			(effects
				(font
					(size 0.7 0.7)
					(thickness 0.15)
				)
				(justify left bottom)
			)
		)
		(fp_text user "License: Apache-2.0"
			(at -2.644 26.2 180)
			(layer "F.Fab")
			(effects
				(font
					(size 0.7 0.7)
					(thickness 0.15)
				)
				(justify left bottom)
			)
		)
		(pad "" np_thru_hole circle
			(at 0 8.9 180)
			(size 3.25 3.25)
			(drill 3.25)
			(layers "*.Cu" "*.Mask")
		)
		(pad "" np_thru_hole circle
			(at 11.429 8.9 180)
			(size 3.25 3.25)
			(drill 3.25)
			(layers "*.Cu" "*.Mask")
		)
		(pad "1" thru_hole circle
			(at 0 0 180)
			(size 1.397 1.397)
			(drill 0.889)
			(layers "*.Cu" "*.Mask")
			(remove_unused_layers no)
			(net 88 "/Compute module/ETHERNET.D0_P")
			(pinfunction "P1")
			(pintype "bidirectional")
		)
		(pad "2" thru_hole circle
			(at 1.269 2.539 180)
			(size 1.397 1.397)
			(drill 0.889)
			(layers "*.Cu" "*.Mask")
			(remove_unused_layers no)
			(net 84 "/Compute module/ETHERNET.D0_N")
			(pinfunction "P2")
			(pintype "bidirectional")
		)
		(pad "3" thru_hole circle
			(at 2.539 0 180)
			(size 1.397 1.397)
			(drill 0.889)
			(layers "*.Cu" "*.Mask")
			(remove_unused_layers no)
			(net 80 "/Compute module/ETHERNET.D1_P")
			(pinfunction "P3")
			(pintype "bidirectional")
		)
		(pad "4" thru_hole circle
			(at 3.809 2.539 180)
			(size 1.397 1.397)
			(drill 0.889)
			(layers "*.Cu" "*.Mask")
			(remove_unused_layers no)
			(net 91 "Net-(J401-P4)")
			(pinfunction "P4")
			(pintype "bidirectional")
		)
		(pad "5" thru_hole circle
			(at 5.078 0 180)
			(size 1.397 1.397)
			(drill 0.889)
			(layers "*.Cu" "*.Mask")
			(remove_unused_layers no)
			(net 91 "Net-(J401-P4)")
			(pinfunction "P5")
			(pintype "bidirectional")
		)
		(pad "6" thru_hole circle
			(at 6.349 2.539 180)
			(size 1.397 1.397)
			(drill 0.889)
			(layers "*.Cu" "*.Mask")
			(remove_unused_layers no)
			(net 82 "/Compute module/ETHERNET.D1_N")
			(pinfunction "P6")
			(pintype "bidirectional")
		)
		(pad "7" thru_hole circle
			(at 7.618 0 180)
			(size 1.397 1.397)
			(drill 0.889)
			(layers "*.Cu" "*.Mask")
			(remove_unused_layers no)
			(net 85 "/Compute module/ETHERNET.D2_P")
			(pinfunction "P7")
			(pintype "bidirectional")
		)
		(pad "8" thru_hole circle
			(at 8.89 2.539 180)
			(size 1.397 1.397)
			(drill 0.889)
			(layers "*.Cu" "*.Mask")
			(remove_unused_layers no)
			(net 83 "/Compute module/ETHERNET.D2_N")
			(pinfunction "P8")
			(pintype "bidirectional")
		)
		(pad "9" thru_hole circle
			(at 10.159 0 180)
			(size 1.397 1.397)
			(drill 0.889)
			(layers "*.Cu" "*.Mask")
			(remove_unused_layers no)
			(net 79 "/Compute module/ETHERNET.D3_P")
			(pinfunction "P9")
			(pintype "bidirectional")
		)
		(pad "10" thru_hole circle
			(at 11.429 2.539 180)
			(size 1.397 1.397)
			(drill 0.889)
			(layers "*.Cu" "*.Mask")
			(remove_unused_layers no)
			(net 81 "/Compute module/ETHERNET.D3_N")
			(pinfunction "P10")
			(pintype "bidirectional")
		)
		(pad "11" thru_hole circle
			(at 0 5.078 180)
			(size 1.397 1.397)
			(drill 0.889)
			(layers "*.Cu" "*.Mask")
			(remove_unused_layers no)
			(net 61 "/Ethernet/PAIR_12")
			(pinfunction "VC1")
			(pintype "bidirectional")
		)
		(pad "12" thru_hole circle
			(at 2.539 6.339 180)
			(size 1.397 1.397)
			(drill 0.889)
			(layers "*.Cu" "*.Mask")
			(remove_unused_layers no)
			(net 62 "/Ethernet/PAIR_36")
			(pinfunction "VC2")
			(pintype "bidirectional")
		)
		(pad "13" thru_hole circle
			(at 8.89 6.339 180)
			(size 1.397 1.397)
			(drill 0.889)
			(layers "*.Cu" "*.Mask")
			(remove_unused_layers no)
			(net 64 "/Ethernet/PAIR_78")
			(pinfunction "VC3")
			(pintype "bidirectional")
		)
		(pad "14" thru_hole circle
			(at 11.429 5.07 180)
			(size 1.397 1.397)
			(drill 0.889)
			(layers "*.Cu" "*.Mask")
			(remove_unused_layers no)
			(net 63 "/Ethernet/PAIR_910")
			(pinfunction "VC4")
			(pintype "bidirectional")
		)
		(pad "15" thru_hole circle
			(at -0.927 12.958 180)
			(size 1.524 1.524)
			(drill 1.016)
			(layers "*.Cu" "*.Mask")
			(remove_unused_layers no)
			(net 9 "+3V3")
			(pinfunction "LED_GRN+")
			(pintype "passive")
		)
		(pad "16" thru_hole circle
			(at 1.614 12.958 180)
			(size 1.524 1.524)
			(drill 1.016)
			(layers "*.Cu" "*.Mask")
			(remove_unused_layers no)
			(net 176 "Net-(J401-LED_GRN-)")
			(pinfunction "LED_GRN-")
			(pintype "passive")
		)
		(pad "17" thru_hole circle
			(at 9.814 12.958 180)
			(size 1.524 1.524)
			(drill 1.016)
			(layers "*.Cu" "*.Mask")
			(remove_unused_layers no)
			(net 9 "+3V3")
			(pinfunction "LED_YEL+")
			(pintype "passive")
		)
		(pad "18" thru_hole circle
			(at 12.355 12.958 180)
			(size 1.524 1.524)
			(drill 1.016)
			(layers "*.Cu" "*.Mask")
			(remove_unused_layers no)
			(net 175 "Net-(J401-LED_YEL-)")
			(pinfunction "LED_YEL-")
			(pintype "passive")
		)
		(pad "19" thru_hole circle
			(at -2.136 5.85 180)
			(size 2.1 2.1)
			(drill 1.6)
			(layers "*.Cu" "*.Mask")
			(remove_unused_layers no)
			(net 92 "Net-(C403-Pad1)")
			(pinfunction "SHIELD")
			(pintype "passive")
		)
		(pad "20" thru_hole circle
			(at 13.563 5.85 180)
			(size 2.1082 2.1082)
			(drill 1.6002)
			(layers "*.Cu" "*.Mask")
			(remove_unused_layers no)
			(net 92 "Net-(C403-Pad1)")
			(pinfunction "SHIELD")
			(pintype "passive")
		)
	)
)
